(kicad_pcb
	(version 20260206)
	(generator "pcbnew")
	(generator_version "10.0")
	(general
		(thickness 1.6)
		(legacy_teardrops no)
	)
	(paper "A4")
	(title_block
		(title "v2-pdb — ms_pdb_v2.brd")
		(comment 1 "Open CloudServer (Microsoft) / footprints 326-326 of 348")
	)
	(layers
		(0 "F.Cu" signal "TOP")
		(4 "In1.Cu" signal "GND")
		(6 "In2.Cu" signal "IN1")
		(8 "In3.Cu" signal "VCC")
		(10 "In4.Cu" signal "VCC1")
		(12 "In5.Cu" signal "IN2")
		(14 "In6.Cu" signal "GND1")
		(2 "B.Cu" signal "BOTTOM")
		(9 "F.Adhes" user "F.Adhesive")
		(11 "B.Adhes" user "B.Adhesive")
		(13 "F.Paste" user "Package Geometry/Pastemask Top")
		(15 "B.Paste" user "Package Geometry/Pastemask Bottom")
		(5 "F.SilkS" user "Ref Des/Silkscreen Top")
		(7 "B.SilkS" user "Ref Des/Silkscreen Bottom")
		(1 "F.Mask" user "Board Geometry/Soldermask Top")
		(3 "B.Mask" user "Board Geometry/Soldermask Bottom")
		(17 "Dwgs.User" user "User.Drawings")
		(19 "Cmts.User" user "User.Comments")
		(21 "Eco1.User" user "User.Eco1")
		(23 "Eco2.User" user "User.Eco2")
		(25 "Edge.Cuts" user "Board Geometry/Outline")
		(27 "Margin" user)
		(31 "F.CrtYd" user "Package Geometry/Place Bound Top")
		(29 "B.CrtYd" user "Package Geometry/Place Bound Bottom")
		(35 "F.Fab" user "Ref Des/Assembly Top")
		(33 "B.Fab" user "Ref Des/Assembly Bottom")
	)
	(footprint ""
		(layer "B.Cu")
		(at 91.865958 -169.795444)
		(property "Reference" "U5"
			(at 4.088384 0.502412 0)
			(unlocked yes)
			(layer "B.SilkS")
			(effects
				(font
					(size 0.7874 0.5842)
					(thickness 0.1524)
				)
				(justify left mirror)
			)
		)
		(property "Value" ""
			(at 0 0 0)
			(layer "B.Fab")
			(effects
				(font
					(size 1.27 1.27)
				)
				(justify mirror)
			)
		)
		(duplicate_pad_numbers_are_jumpers no)
		(fp_line
			(start -2.5527 -2.0066)
			(end -2.5527 2.0066)
			(stroke
				(width 0.1524)
				(type default)
			)
			(layer "B.SilkS")
		)
		(fp_line
			(start -2.5527 2.0066)
			(end 2.5527 2.0066)
			(stroke
				(width 0.1524)
				(type default)
			)
			(layer "B.SilkS")
		)
		(fp_line
			(start 1.9812 0)
			(end 2.5527 -0.5715)
			(stroke
				(width 0.1524)
				(type default)
			)
			(layer "B.SilkS")
		)
		(fp_line
			(start 2.5527 -2.0066)
			(end -2.5527 -2.0066)
			(stroke
				(width 0.1524)
				(type default)
			)
			(layer "B.SilkS")
		)
		(fp_line
			(start 2.5527 -0.5715)
			(end 2.5527 -2.0066)
			(stroke
				(width 0.1524)
				(type default)
			)
			(layer "B.SilkS")
		)
		(fp_line
			(start 2.5527 0.5715)
			(end 1.9812 0)
			(stroke
				(width 0.1524)
				(type default)
			)
			(layer "B.SilkS")
		)
		(fp_line
			(start 2.5527 2.0066)
			(end 2.5527 0.5715)
			(stroke
				(width 0.1524)
				(type default)
			)
			(layer "B.SilkS")
		)
		(fp_circle
			(center 2.032 1.524)
			(end 2.286 1.524)
			(stroke
				(width 0.1524)
				(type default)
			)
			(fill no)
			(layer "B.SilkS")
		)
		(fp_rect
			(start 2.5527 3.6703)
			(end -2.5527 -3.6703)
			(stroke
				(width 0)
				(type default)
			)
			(fill no)
			(layer "B.CrtYd")
		)
		(fp_line
			(start -2.549906 -2.249932)
			(end -2.549906 2.249932)
			(stroke
				(width 0.1)
				(type default)
			)
			(layer "B.Fab")
		)
		(fp_line
			(start -2.549906 2.249932)
			(end 2.549906 2.249932)
			(stroke
				(width 0.1)
				(type default)
			)
			(layer "B.Fab")
		)
		(fp_line
			(start 2.549906 -2.249932)
			(end -2.549906 -2.249932)
			(stroke
				(width 0.1)
				(type default)
			)
			(layer "B.Fab")
		)
		(fp_line
			(start 2.549906 2.249932)
			(end 2.549906 -2.249932)
			(stroke
				(width 0.1)
				(type default)
			)
			(layer "B.Fab")
		)
		(pad "1" smd rect
			(at 1.949958 2.921 180)
			(size 0.3556 1.4986)
			(layers "B.Cu" "B.Mask" "B.Paste")
			(net "PSU_ALERT_N")
		)
		(pad "2" smd rect
			(at 1.299972 2.921 180)
			(size 0.3556 1.4986)
			(layers "B.Cu" "B.Mask" "B.Paste")
			(net "B7_PSU_ALERT_N")
		)
		(pad "3" smd rect
			(at 0.649986 2.921 180)
			(size 0.3556 1.4986)
			(layers "B.Cu" "B.Mask" "B.Paste")
			(net "PSU_ALERT_N")
		)
		(pad "4" smd rect
			(at 0 2.921 180)
			(size 0.3556 1.4986)
			(layers "B.Cu" "B.Mask" "B.Paste")
			(net "B8_PSU_ALERT_N")
		)
		(pad "5" smd rect
			(at -0.649986 2.921 180)
			(size 0.3556 1.4986)
			(layers "B.Cu" "B.Mask" "B.Paste")
			(net "PSU_ALERT_N")
		)
		(pad "6" smd rect
			(at -1.299972 2.921 180)
			(size 0.3556 1.4986)
			(layers "B.Cu" "B.Mask" "B.Paste")
			(net "B9_PSU_ALERT_N")
		)
		(pad "7" smd rect
			(at -1.949958 2.921 180)
			(size 0.3556 1.4986)
			(layers "B.Cu" "B.Mask" "B.Paste")
			(net "GND")
		)
		(pad "8" smd rect
			(at -1.949958 -2.921 180)
			(size 0.3556 1.4986)
			(layers "B.Cu" "B.Mask" "B.Paste")
			(net "B10_PSU_ALERT_N")
		)
		(pad "9" smd rect
			(at -1.299972 -2.921 180)
			(size 0.3556 1.4986)
			(layers "B.Cu" "B.Mask" "B.Paste")
			(net "PSU_ALERT_N")
		)
		(pad "10" smd rect
			(at -0.649986 -2.921 180)
			(size 0.3556 1.4986)
			(layers "B.Cu" "B.Mask" "B.Paste")
			(net "B11_PSU_ALERT_N")
		)
		(pad "11" smd rect
			(at 0 -2.921 180)
			(size 0.3556 1.4986)
			(layers "B.Cu" "B.Mask" "B.Paste")
			(net "PSU_ALERT_N")
		)
		(pad "12" smd rect
			(at 0.649986 -2.921 180)
			(size 0.3556 1.4986)
			(layers "B.Cu" "B.Mask" "B.Paste")
			(net "B12_PSU_ALERT_N")
		)
		(pad "13" smd rect
			(at 1.299972 -2.921 180)
			(size 0.3556 1.4986)
			(layers "B.Cu" "B.Mask" "B.Paste")
			(net "PSU_ALERT_N")
		)
		(pad "14" smd rect
			(at 1.949958 -2.921 180)
			(size 0.3556 1.4986)
			(layers "B.Cu" "B.Mask" "B.Paste")
			(net "P3V3_BUF")
		)
	)
)
